FILE_TYPE = CONNECTIVITY;
{Allegro Design Entry HDL 17.2-2016 S081 (4005846) 1/11/2022}
"PAGE_NUMBER" = 187;
0"NC";
1"P3V3_AUX\g";
2"P3V3_AUX\g";
3"P3V3_AUX\g";
4"P3V3_AUX\g";
5"P3V3_AUX\g";
6"P3V3_AUX\g";
7"P3V3_AUX\g";
8"P3V3_AUX\g";
9"P3V3_AUX\g";
10"GND\g";
11"GND\g";
12"GND\g";
13"GND\g";
14"GND\g";
15"GND\g";
16"GND\g";
17"FM_PCH_XTALSEL";
18"FM_PCH_VISA_DEFAULT";
19"FM_ESPI_FLASH_MODE";
20"FM_PCH_SKIP_RTC_CLOCK";
21"FM_PCH_EXTERNALCLKMODE";
22"FM_ESPI_CS_SWIZZLE";
23"FM_JTAG_ODT_DISABLE"CDS_PHYS_NET_NAME"FM_JTAG_ODT_DISABLE";
24"FM_PCH_IO_EXPANDER";
25"FM_LT_KEY_DOWNGRADE_N";
%"UNIVERSAL_GND"
"1","(-2125,200)","0","logical_power","I11";
;
CDS_LIB"logical_power"
HDL_POWER"GND"
ROOM"IO_SLOT";
"A"16;
%"UNIVERSAL_POWER"
"1","(-2125,-875)","0","logical_power","I12";
;
HDL_POWER"P3V3_AUX"
CDS_LIB"logical_power";
"A"9;
%"Q_RES"
"2","(-2125,-1125)","0","pure_quanta","I13";
;
PART_NUMBER"CS21002FB06"
VALUE"1K"
WATTAGE"1/16W"
PACK_TYPE"0402LF"
MATERIAL"EMPTY"
TOLERANCE"1%"
$LOCATION"R623"
CDS_LIB"pure_quanta"
CDS_LOCATION"R623"
$SEC"1"
CDS_SEC"1";
"A"
$PN"1"9;
"B"
$PN"2"17;
%"Q_RES"
"2","(-2125,-1650)","0","pure_quanta","I14";
;
PART_NUMBER"CS31002FB08"
VALUE"10K"
PACK_TYPE"0402LF"
MATERIAL"CHIP"
WATTAGE"1/16W"
TOLERANCE"1%"
$LOCATION"R624"
CDS_LIB"pure_quanta"
CDS_LOCATION"R624"
$SEC"1"
CDS_SEC"1";
"A"
$PN"1"17;
"B"
$PN"2"15;
%"UNIVERSAL_GND"
"1","(-2125,-1875)","0","logical_power","I15";
;
CDS_LIB"logical_power"
HDL_POWER"GND"
ROOM"IO_SLOT";
"A"15;
%"UNIVERSAL_POWER"
"1","(-5300,3200)","0","logical_power","I17";
;
HDL_POWER"P3V3_AUX"
CDS_LIB"logical_power";
"A"8;
%"Q_RES"
"2","(-5300,2950)","0","pure_quanta","I18";
;
PART_NUMBER"CS31002FB08"
VALUE"10K"
TOLERANCE"1%"
PACK_TYPE"0402LF"
WATTAGE"1/16W"
MATERIAL"CHIP"
$LOCATION"R613"
CDS_LIB"pure_quanta"
CDS_LOCATION"R613"
$SEC"1"
CDS_SEC"1";
"A"
$PN"1"8;
"B"
$PN"2"23;
%"UNIVERSAL_POWER"
"1","(-8425,3200)","0","logical_power","I20";
;
HDL_POWER"P3V3_AUX"
CDS_LIB"logical_power";
"A"7;
%"Q_RES"
"2","(-8425,2950)","0","pure_quanta","I21";
;
PART_NUMBER"CS21002FB06"
PACK_TYPE"0402LF"
MATERIAL"EMPTY"
VALUE"1K"
WATTAGE"1/16W"
TOLERANCE"1%"
$LOCATION"R607"
CDS_LIB"pure_quanta"
CDS_LOCATION"R607"
$SEC"1"
CDS_SEC"1";
"A"
$PN"1"7;
"B"
$PN"2"19;
%"Q_RES"
"2","(-5300,2425)","0","pure_quanta","I23";
;
PART_NUMBER"CS21002FB06"
PACK_TYPE"0402LF"
VALUE"1K"
WATTAGE"1/16W"
MATERIAL"EMPTY"
TOLERANCE"1%"
$LOCATION"R614"
CDS_LIB"pure_quanta"
CDS_LOCATION"R614"
$SEC"1"
CDS_SEC"1";
"A"
$PN"1"23;
"B"
$PN"2"14;
%"UNIVERSAL_GND"
"1","(-5300,2200)","0","logical_power","I24";
;
CDS_LIB"logical_power"
HDL_POWER"GND"
ROOM"IO_SLOT";
"A"14;
%"UNIVERSAL_POWER"
"1","(-5300,1200)","0","logical_power","I25";
;
HDL_POWER"P3V3_AUX"
CDS_LIB"logical_power";
"A"6;
%"UNIVERSAL_POWER"
"1","(-5300,-900)","0","logical_power","I30";
;
HDL_POWER"P3V3_AUX"
CDS_LIB"logical_power";
"A"5;
%"UNIVERSAL_GND"
"1","(-5300,-1850)","0","logical_power","I35";
;
CDS_LIB"logical_power"
HDL_POWER"GND"
ROOM"IO_SLOT";
"A"13;
%"Q_RES"
"2","(-8425,2425)","0","pure_quanta","I36";
;
PART_NUMBER"CS31002FB08"
VALUE"10K"
MATERIAL"CHIP"
PACK_TYPE"0402LF"
TOLERANCE"1%"
WATTAGE"1/16W"
$LOCATION"R608"
CDS_LIB"pure_quanta"
CDS_LOCATION"R608"
$SEC"1"
CDS_SEC"1";
"A"
$PN"1"19;
"B"
$PN"2"12;
%"UNIVERSAL_GND"
"1","(-8425,2200)","0","logical_power","I37";
;
CDS_LIB"logical_power"
HDL_POWER"GND"
ROOM"IO_SLOT";
"A"12;
%"UNIVERSAL_POWER"
"1","(-8425,1200)","0","logical_power","I38";
;
HDL_POWER"P3V3_AUX"
CDS_LIB"logical_power";
"A"4;
%"Q_RES"
"2","(-8425,950)","0","pure_quanta","I39";
;
PART_NUMBER"CS21002FB06"
WATTAGE"1/16W"
VALUE"1K"
MATERIAL"EMPTY"
PACK_TYPE"0402LF"
TOLERANCE"1%"
$LOCATION"R609"
CDS_LIB"pure_quanta"
CDS_LOCATION"R609"
$SEC"1"
CDS_SEC"1";
"A"
$PN"1"4;
"B"
$PN"2"22;
%"Q_RES"
"2","(-8425,425)","0","pure_quanta","I40";
;
PART_NUMBER"CS31002FB08"
MATERIAL"CHIP"
TOLERANCE"1%"
VALUE"10K"
PACK_TYPE"0402LF"
WATTAGE"1/16W"
$LOCATION"R610"
CDS_LIB"pure_quanta"
CDS_LOCATION"R610"
$SEC"1"
CDS_SEC"1";
"A"
$PN"1"22;
"B"
$PN"2"11;
%"UNIVERSAL_GND"
"1","(-8425,200)","0","logical_power","I41";
;
CDS_LIB"logical_power"
HDL_POWER"GND"
ROOM"IO_SLOT";
"A"11;
%"UNIVERSAL_POWER"
"1","(-8425,-850)","0","logical_power","I42";
;
HDL_POWER"P3V3_AUX"
CDS_LIB"logical_power";
"A"3;
%"Q_RES"
"2","(-8425,-1100)","0","pure_quanta","I43";
;
PART_NUMBER"CS21002FB06"
VALUE"1K"
PACK_TYPE"0402LF"
WATTAGE"1/16W"
MATERIAL"CHIP"
TOLERANCE"1%"
$LOCATION"R611"
CDS_LIB"pure_quanta"
CDS_LOCATION"R611"
$SEC"1"
CDS_SEC"1";
"A"
$PN"1"3;
"B"
$PN"2"21;
%"Q_RES"
"2","(-8425,-1625)","0","pure_quanta","I44";
;
PART_NUMBER"CS31002FB08"
TOLERANCE"1%"
VALUE"10K"
PACK_TYPE"0402LF"
MATERIAL"EMPTY"
WATTAGE"1/16W"
$LOCATION"R612"
CDS_LIB"pure_quanta"
CDS_LOCATION"R612"
$SEC"1"
CDS_SEC"1";
"A"
$PN"1"21;
"B"
$PN"2"10;
%"UNIVERSAL_GND"
"1","(-8425,-1850)","0","logical_power","I45";
;
CDS_LIB"logical_power"
HDL_POWER"GND"
ROOM"IO_SLOT";
"A"10;
%"UNIVERSAL_POWER"
"1","(-2125,3200)","0","logical_power","I47";
;
HDL_POWER"P3V3_AUX"
CDS_LIB"logical_power";
"A"2;
%"Q_RES"
"2","(-2125,2950)","0","pure_quanta","I48";
;
PART_NUMBER"CS31002FB08"
PACK_TYPE"0402LF"
TOLERANCE"1%"
WATTAGE"1/16W"
MATERIAL"CHIP"
VALUE"10K"
$LOCATION"R619"
CDS_LIB"pure_quanta"
CDS_LOCATION"R619"
$SEC"1"
CDS_SEC"1";
"A"
$PN"1"2;
"B"
$PN"2"25;
%"Q_RES"
"2","(-5300,950)","0","pure_quanta","I51";
;
PART_NUMBER"CS21002FB06"
PACK_TYPE"0402LF"
VALUE"1K"
MATERIAL"CHIP"
WATTAGE"1/16W"
TOLERANCE"1%"
$LOCATION"R615"
CDS_LIB"pure_quanta"
CDS_LOCATION"R615"
$SEC"1"
CDS_SEC"1";
"A"
$PN"1"6;
"B"
$PN"2"18;
%"Q_RES"
"2","(-5300,-1625)","0","pure_quanta","I53";
;
PART_NUMBER"CS31002FB08"
VALUE"10K"
TOLERANCE"1%"
MATERIAL"CHIP"
PACK_TYPE"0402LF"
WATTAGE"1/16W"
$LOCATION"R618"
CDS_LIB"pure_quanta"
CDS_LOCATION"R618"
$SEC"1"
CDS_SEC"1";
"A"
$PN"1"24;
"B"
$PN"2"13;
%"Q_RES"
"2","(-5300,-1150)","0","pure_quanta","I54";
;
PART_NUMBER"CS21002FB06"
WATTAGE"1/16W"
VALUE"1K"
MATERIAL"EMPTY"
PACK_TYPE"0402LF"
TOLERANCE"1%"
$LOCATION"R617"
CDS_LIB"pure_quanta"
CDS_LOCATION"R617"
$SEC"1"
CDS_SEC"1";
"A"
$PN"1"5;
"B"
$PN"2"24;
%"Q_RES"
"2","(-2125,900)","0","pure_quanta","I55";
;
PART_NUMBER"CS21002FB06"
PACK_TYPE"0402LF"
MATERIAL"EMPTY"
WATTAGE"1/16W"
VALUE"1K"
TOLERANCE"1%"
$LOCATION"R621"
CDS_LIB"pure_quanta"
CDS_LOCATION"R621"
$SEC"1"
CDS_SEC"1";
"A"
$PN"1"1;
"B"
$PN"2"20;
%"Q_RES"
"2","(-2125,425)","0","pure_quanta","I56";
;
PART_NUMBER"CS21002FB06"
WATTAGE"1/16W"
MATERIAL"CHIP"
PACK_TYPE"0402LF"
VALUE"1K"
TOLERANCE"1%"
$LOCATION"R622"
CDS_LIB"pure_quanta"
CDS_LOCATION"R622"
$SEC"1"
CDS_SEC"1";
"A"
$PN"1"20;
"B"
$PN"2"16;
%"UNIVERSAL_POWER"
"1","(-2125,1150)","0","logical_power","I8";
;
HDL_POWER"P3V3_AUX"
CDS_LIB"logical_power";
"A"1;
END.
